# SCM (Grand Teton) — schematic netlist excerpt (pin names and nets, part order shuffled) for the footprints in the layout excerpt that follows; sources: Cadence DE-HDL packaged netlist, KiCad conversion of 12092022_DA0F0TMDCD0_F0T_Management_Board_D_brd_V3_OCP.brd

R709  Q_RES  2.2K 5% CHIP  pkg 0402LF  page 52 : A = P3V3_RGM ; B = PWRGD_P3V3_RGM_R
C296  Q_CAP  0.1UF 25V 10% X7R  pkg 0402  page 52 : A = P3V3_LDO ; B = GND

(kicad_pcb
	(version 20260206)
	(generator "pcbnew")
	(generator_version "10.0")
	(general
		(thickness 1.6)
		(legacy_teardrops no)
	)
	(paper "A4")
	(title_block
		(title "12092022_DA0F0TMDCD0_F0T_Management_Board_D_brd_V3_OCP.brd")
		(comment 1 "Grand Teton / footprints 15-16 of 1440")
	)
	(layers
		(0 "F.Cu" signal "TOP")
		(4 "In1.Cu" signal "GND")
		(6 "In2.Cu" signal "IN1")
		(8 "In3.Cu" signal "GND1")
		(10 "In4.Cu" signal "IN2")
		(12 "In5.Cu" signal "VCC")
		(14 "In6.Cu" signal "VCC1")
		(16 "In7.Cu" signal "IN3")
		(18 "In8.Cu" signal "GND2")
		(20 "In9.Cu" signal "IN4")
		(22 "In10.Cu" signal "GND3")
		(2 "B.Cu" signal "BOTTOM")
		(9 "F.Adhes" user "F.Adhesive")
		(11 "B.Adhes" user "B.Adhesive")
		(13 "F.Paste" user "Package Geometry/Pastemask Top")
		(15 "B.Paste" user "Package Geometry/Pastemask Bottom")
		(5 "F.SilkS" user "Ref Des/Silkscreen Top")
		(7 "B.SilkS" user "Ref Des/Silkscreen Bottom")
		(1 "F.Mask" user "Board Geometry/Soldermask Top")
		(3 "B.Mask" user "Board Geometry/Soldermask Bottom")
		(17 "Dwgs.User" user "User.Drawings")
		(19 "Cmts.User" user "User.Comments")
		(21 "Eco1.User" user "User.Eco1")
		(23 "Eco2.User" user "User.Eco2")
		(25 "Edge.Cuts" user "Board Geometry/Outline")
		(27 "Margin" user)
		(31 "F.CrtYd" user "Package Geometry/Place Bound Top")
		(29 "B.CrtYd" user "Package Geometry/Place Bound Bottom")
		(35 "F.Fab" user "Ref Des/Assembly Top")
		(33 "B.Fab" user "Ref Des/Assembly Bottom")
	)
	(footprint ""
		(layer "F.Cu")
		(at 15.3416 -47.8536 -90)
		(property "Reference" "C296"
			(at 0 0 270)
			(layer "F.SilkS")
			(hide yes)
			(effects
				(font
					(size 1.27 1.27)
				)
			)
		)
		(property "Value" ""
			(at 0 0 270)
			(layer "F.Fab")
			(effects
				(font
					(size 1.27 1.27)
				)
			)
		)
		(duplicate_pad_numbers_are_jumpers no)
		(fp_line
			(start -0.7874 0.4064)
			(end -0.7874 -0.4064)
			(stroke
				(width 0.1524)
				(type default)
			)
			(layer "F.SilkS")
		)
		(fp_line
			(start 0.7874 0.4064)
			(end -0.7874 0.4064)
			(stroke
				(width 0.1524)
				(type default)
			)
			(layer "F.SilkS")
		)
		(fp_line
			(start -0.7874 -0.4064)
			(end 0.7874 -0.4064)
			(stroke
				(width 0.1524)
				(type default)
			)
			(layer "F.SilkS")
		)
		(fp_line
			(start 0.7874 -0.4064)
			(end 0.7874 0.4064)
			(stroke
				(width 0.1524)
				(type default)
			)
			(layer "F.SilkS")
		)
		(fp_line
			(start -0.67945 0.3048)
			(end -0.67945 -0.305054)
			(stroke
				(width 0.1)
				(type default)
			)
			(layer "F.Fab")
		)
		(fp_line
			(start -0.12065 0.3048)
			(end -0.67945 0.3048)
			(stroke
				(width 0.1)
				(type default)
			)
			(layer "F.Fab")
		)
		(fp_line
			(start 0.120396 0.3048)
			(end 0.120396 0.2794)
			(stroke
				(width 0.1)
				(type default)
			)
			(layer "F.Fab")
		)
		(fp_line
			(start 0.67945 0.3048)
			(end 0.120396 0.3048)
			(stroke
				(width 0.1)
				(type default)
			)
			(layer "F.Fab")
		)
		(fp_line
			(start -0.12065 0.2794)
			(end -0.12065 0.3048)
			(stroke
				(width 0.1)
				(type default)
			)
			(layer "F.Fab")
		)
		(fp_line
			(start 0.120396 0.2794)
			(end -0.12065 0.2794)
			(stroke
				(width 0.1)
				(type default)
			)
			(layer "F.Fab")
		)
		(fp_line
			(start -0.12065 -0.2794)
			(end 0.12065 -0.2794)
			(stroke
				(width 0.1)
				(type default)
			)
			(layer "F.Fab")
		)
		(fp_line
			(start 0.12065 -0.2794)
			(end 0.12065 -0.3048)
			(stroke
				(width 0.1)
				(type default)
			)
			(layer "F.Fab")
		)
		(fp_line
			(start 0.12065 -0.3048)
			(end 0.67945 -0.3048)
			(stroke
				(width 0.1)
				(type default)
			)
			(layer "F.Fab")
		)
		(fp_line
			(start 0.67945 -0.3048)
			(end 0.67945 0.3048)
			(stroke
				(width 0.1)
				(type default)
			)
			(layer "F.Fab")
		)
		(fp_line
			(start -0.67945 -0.305054)
			(end -0.12065 -0.305054)
			(stroke
				(width 0.1)
				(type default)
			)
			(layer "F.Fab")
		)
		(fp_line
			(start -0.12065 -0.305054)
			(end -0.12065 -0.2794)
			(stroke
				(width 0.1)
				(type default)
			)
			(layer "F.Fab")
		)
		(pad "1" smd circle
			(at -0.40005 0 270)
			(size 0 0)
			(layers "F.Cu" "F.Mask" "F.Paste")
			(net "P3V3_LDO")
		)
		(pad "2" smd circle
			(at 0.40005 0 270)
			(size 0 0)
			(layers "F.Cu" "F.Mask" "F.Paste")
			(net "GND")
		)
	)
	(footprint ""
		(layer "F.Cu")
		(at 70.8025 -31.3055)
		(property "Reference" "R709"
			(at 0 0 0)
			(layer "F.SilkS")
			(hide yes)
			(effects
				(font
					(size 1.27 1.27)
				)
			)
		)
		(property "Value" ""
			(at 0 0 0)
			(layer "F.Fab")
			(effects
				(font
					(size 1.27 1.27)
				)
			)
		)
		(duplicate_pad_numbers_are_jumpers no)
		(fp_line
			(start -0.7874 -0.4064)
			(end 0.7874 -0.4064)
			(stroke
				(width 0.1524)
				(type default)
			)
			(layer "F.SilkS")
		)
		(fp_line
			(start -0.7874 0.4064)
			(end -0.7874 -0.4064)
			(stroke
				(width 0.1524)
				(type default)
			)
			(layer "F.SilkS")
		)
		(fp_line
			(start 0.7874 -0.4064)
			(end 0.7874 0.4064)
			(stroke
				(width 0.1524)
				(type default)
			)
			(layer "F.SilkS")
		)
		(fp_line
			(start 0.7874 0.4064)
			(end -0.7874 0.4064)
			(stroke
				(width 0.1524)
				(type default)
			)
			(layer "F.SilkS")
		)
		(fp_line
			(start -0.67945 -0.305054)
			(end -0.12065 -0.305054)
			(stroke
				(width 0.1)
				(type default)
			)
			(layer "F.Fab")
		)
		(fp_line
			(start -0.67945 0.3048)
			(end -0.67945 -0.305054)
			(stroke
				(width 0.1)
				(type default)
			)
			(layer "F.Fab")
		)
		(fp_line
			(start -0.12065 -0.305054)
			(end -0.12065 -0.2794)
			(stroke
				(width 0.1)
				(type default)
			)
			(layer "F.Fab")
		)
		(fp_line
			(start -0.12065 -0.2794)
			(end 0.12065 -0.2794)
			(stroke
				(width 0.1)
				(type default)
			)
			(layer "F.Fab")
		)
		(fp_line
			(start -0.12065 0.2794)
			(end -0.12065 0.3048)
			(stroke
				(width 0.1)
				(type default)
			)
			(layer "F.Fab")
		)
		(fp_line
			(start -0.12065 0.3048)
			(end -0.67945 0.3048)
			(stroke
				(width 0.1)
				(type default)
			)
			(layer "F.Fab")
		)
		(fp_line
			(start 0.120396 0.2794)
			(end -0.12065 0.2794)
			(stroke
				(width 0.1)
				(type default)
			)
			(layer "F.Fab")
		)
		(fp_line
			(start 0.120396 0.3048)
			(end 0.120396 0.2794)
			(stroke
				(width 0.1)
				(type default)
			)
			(layer "F.Fab")
		)
		(fp_line
			(start 0.12065 -0.3048)
			(end 0.67945 -0.3048)
			(stroke
				(width 0.1)
				(type default)
			)
			(layer "F.Fab")
		)
		(fp_line
			(start 0.12065 -0.2794)
			(end 0.12065 -0.3048)
			(stroke
				(width 0.1)
				(type default)
			)
			(layer "F.Fab")
		)
		(fp_line
			(start 0.67945 -0.3048)
			(end 0.67945 0.3048)
			(stroke
				(width 0.1)
				(type default)
			)
			(layer "F.Fab")
		)
		(fp_line
			(start 0.67945 0.3048)
			(end 0.120396 0.3048)
			(stroke
				(width 0.1)
				(type default)
			)
			(layer "F.Fab")
		)
		(pad "1" smd circle
			(at -0.40005 0)
			(size 0 0)
			(layers "F.Cu" "F.Mask" "F.Paste")
			(net "P3V3_RGM")
		)
		(pad "2" smd circle
			(at 0.40005 0)
			(size 0 0)
			(layers "F.Cu" "F.Mask" "F.Paste")
			(net "PWRGD_P3V3_RGM_R")
		)
	)
)
